G04 #@! TF.GenerationSoftware,KiCad,Pcbnew,(5.0.1)-3*
G04 #@! TF.CreationDate,2019-04-10T15:36:06+02:00*
G04 #@! TF.ProjectId,discovery,646973636F766572792E6B696361645F,rev?*
G04 #@! TF.SameCoordinates,PX4c4640PY8a48028*
G04 #@! TF.FileFunction,Glue,Bot*
G04 #@! TF.FilePolarity,Positive*
%FSLAX46Y46*%
G04 Gerber Fmt 4.6, Leading zero omitted, Abs format (unit mm)*
%MOMM*%
%LPD*%
G01*
G04 APERTURE LIST*
G04 APERTURE END LIST*
M02*
